(kicad_pcb
	(version 20260206)
	(generator "pcbnew")
	(generator_version "10.0")
	(general
		(thickness 1.6)
		(legacy_teardrops no)
	)
	(paper "A4")
	(title_block
		(title "01162023_DA0F0TEBIF0_F0T_Expander_BD_F_brd_V02_OCP.brd")
		(comment 1 "Grand Teton / footprints 2573-2577 of 9728")
	)
	(layers
		(0 "F.Cu" signal "TOP")
		(4 "In1.Cu" signal "GND")
		(6 "In2.Cu" signal "VCC")
		(8 "In3.Cu" signal "VCC1")
		(10 "In4.Cu" signal "GND1")
		(12 "In5.Cu" signal "IN1")
		(14 "In6.Cu" signal "GND2")
		(16 "In7.Cu" signal "IN2")
		(18 "In8.Cu" signal "GND3")
		(20 "In9.Cu" signal "IN3")
		(22 "In10.Cu" signal "GND4")
		(24 "In11.Cu" signal "IN4")
		(26 "In12.Cu" signal "GND5")
		(28 "In13.Cu" signal "IN5")
		(30 "In14.Cu" signal "GND6")
		(32 "In15.Cu" signal "IN6")
		(34 "In16.Cu" signal "GND7")
		(2 "B.Cu" signal "BOTTOM")
		(9 "F.Adhes" user "F.Adhesive")
		(11 "B.Adhes" user "B.Adhesive")
		(13 "F.Paste" user "Package Geometry/Pastemask Top")
		(15 "B.Paste" user "Package Geometry/Pastemask Bottom")
		(5 "F.SilkS" user "Ref Des/Silkscreen Top")
		(7 "B.SilkS" user "Ref Des/Silkscreen Bottom")
		(1 "F.Mask" user "Board Geometry/Soldermask Top")
		(3 "B.Mask" user "Board Geometry/Soldermask Bottom")
		(17 "Dwgs.User" user "User.Drawings")
		(19 "Cmts.User" user "User.Comments")
		(21 "Eco1.User" user "User.Eco1")
		(23 "Eco2.User" user "User.Eco2")
		(25 "Edge.Cuts" user "Board Geometry/Outline")
		(27 "Margin" user)
		(31 "F.CrtYd" user "Package Geometry/Place Bound Top")
		(29 "B.CrtYd" user "Package Geometry/Place Bound Bottom")
		(35 "F.Fab" user "Ref Des/Assembly Top")
		(33 "B.Fab" user "Ref Des/Assembly Bottom")
	)
	(footprint ""
		(layer "F.Cu")
		(at 159.72282 -22.867366 90)
		(property "Reference" "C3911"
			(at 0 0 90)
			(layer "F.SilkS")
			(hide yes)
			(effects
				(font
					(size 1.27 1.27)
				)
			)
		)
		(property "Value" ""
			(at 0 0 90)
			(layer "F.Fab")
			(effects
				(font
					(size 1.27 1.27)
				)
			)
		)
		(duplicate_pad_numbers_are_jumpers no)
		(fp_line
			(start 0.7874 -0.4064)
			(end 0.7874 0.4064)
			(stroke
				(width 0.1524)
				(type default)
			)
			(layer "F.SilkS")
		)
		(fp_line
			(start -0.7874 -0.4064)
			(end 0.7874 -0.4064)
			(stroke
				(width 0.1524)
				(type default)
			)
			(layer "F.SilkS")
		)
		(fp_line
			(start 0.7874 0.4064)
			(end -0.7874 0.4064)
			(stroke
				(width 0.1524)
				(type default)
			)
			(layer "F.SilkS")
		)
		(fp_line
			(start -0.7874 0.4064)
			(end -0.7874 -0.4064)
			(stroke
				(width 0.1524)
				(type default)
			)
			(layer "F.SilkS")
		)
		(fp_line
			(start -0.12065 -0.305054)
			(end -0.12065 -0.2794)
			(stroke
				(width 0.1)
				(type default)
			)
			(layer "F.Fab")
		)
		(fp_line
			(start -0.67945 -0.305054)
			(end -0.12065 -0.305054)
			(stroke
				(width 0.1)
				(type default)
			)
			(layer "F.Fab")
		)
		(fp_line
			(start 0.67945 -0.3048)
			(end 0.67945 0.3048)
			(stroke
				(width 0.1)
				(type default)
			)
			(layer "F.Fab")
		)
		(fp_line
			(start 0.12065 -0.3048)
			(end 0.67945 -0.3048)
			(stroke
				(width 0.1)
				(type default)
			)
			(layer "F.Fab")
		)
		(fp_line
			(start 0.12065 -0.2794)
			(end 0.12065 -0.3048)
			(stroke
				(width 0.1)
				(type default)
			)
			(layer "F.Fab")
		)
		(fp_line
			(start -0.12065 -0.2794)
			(end 0.12065 -0.2794)
			(stroke
				(width 0.1)
				(type default)
			)
			(layer "F.Fab")
		)
		(fp_line
			(start 0.120396 0.2794)
			(end -0.12065 0.2794)
			(stroke
				(width 0.1)
				(type default)
			)
			(layer "F.Fab")
		)
		(fp_line
			(start -0.12065 0.2794)
			(end -0.12065 0.3048)
			(stroke
				(width 0.1)
				(type default)
			)
			(layer "F.Fab")
		)
		(fp_line
			(start 0.67945 0.3048)
			(end 0.120396 0.3048)
			(stroke
				(width 0.1)
				(type default)
			)
			(layer "F.Fab")
		)
		(fp_line
			(start 0.120396 0.3048)
			(end 0.120396 0.2794)
			(stroke
				(width 0.1)
				(type default)
			)
			(layer "F.Fab")
		)
		(fp_line
			(start -0.12065 0.3048)
			(end -0.67945 0.3048)
			(stroke
				(width 0.1)
				(type default)
			)
			(layer "F.Fab")
		)
		(fp_line
			(start -0.67945 0.3048)
			(end -0.67945 -0.305054)
			(stroke
				(width 0.1)
				(type default)
			)
			(layer "F.Fab")
		)
		(pad "1" smd circle
			(at -0.40005 0 90)
			(size 0 0)
			(layers "F.Cu" "F.Mask" "F.Paste")
			(net "P12V_SSD5")
		)
		(pad "2" smd circle
			(at 0.40005 0 90)
			(size 0 0)
			(layers "F.Cu" "F.Mask" "F.Paste")
			(net "GND")
		)
	)
	(footprint ""
		(layer "F.Cu")
		(at 348.04731 -262.322564 -90)
		(property "Reference" "PJ8"
			(at 0 0 270)
			(layer "F.SilkS")
			(hide yes)
			(effects
				(font
					(size 1.27 1.27)
				)
			)
		)
		(property "Value" ""
			(at 0 0 270)
			(layer "F.Fab")
			(effects
				(font
					(size 1.27 1.27)
				)
			)
		)
		(duplicate_pad_numbers_are_jumpers no)
		(pad "1" smd circle
			(at -0.7493 0)
			(size 0 0)
			(layers "F.Cu" "F.Mask" "F.Paste")
			(net "SH_P0V8_PEX3_VSEN3_L")
		)
		(pad "2" smd rect
			(at 0.7493 0 180)
			(size 0.7112 0.8128)
			(layers "F.Cu" "F.Mask" "F.Paste")
			(net "SH_P0V8_PEX3_VSEN3_R")
		)
		(zone
			(layer "F.Cu")
			(hatch none 0.5)
			(connect_pads
				(clearance 0)
			)
			(min_thickness 0.25)
			(keepout
				(tracks allowed)
				(vias not_allowed)
				(pads allowed)
				(copperpour not_allowed)
				(footprints allowed)
			)
			(placement
				(enabled no)
				(sheetname "")
			)
			(fill
				(thermal_gap 0.5)
				(thermal_bridge_width 0.5)
				(island_removal_mode 0)
			)
			(polygon
				(pts
					(xy 347.636084 -261.116064) (xy 348.45371 -261.116064) (xy 348.45371 -263.503664) (xy 347.636084 -263.503664)
				)
			)
		)
	)
	(footprint ""
		(layer "F.Cu")
		(at 244.69471 -157.304994 -90)
		(property "Reference" "PU103"
			(at -3.170936 -0.87249 0)
			(unlocked yes)
			(layer "F.SilkS")
			(effects
				(font
					(size 0.7874 0.5842)
					(thickness 0.1524)
				)
				(justify left)
			)
		)
		(property "Value" ""
			(at 0 0 270)
			(layer "F.Fab")
			(effects
				(font
					(size 1.27 1.27)
				)
			)
		)
		(duplicate_pad_numbers_are_jumpers no)
		(fp_line
			(start -1.549908 2.549906)
			(end -0.753872 2.549906)
			(stroke
				(width 0.1524)
				(type default)
			)
			(layer "F.SilkS")
		)
		(fp_line
			(start -0.245872 2.549906)
			(end 0.245872 2.549906)
			(stroke
				(width 0.1524)
				(type default)
			)
			(layer "F.SilkS")
		)
		(fp_line
			(start 0.753872 2.549906)
			(end 1.549908 2.549906)
			(stroke
				(width 0.1524)
				(type default)
			)
			(layer "F.SilkS")
		)
		(fp_line
			(start 1.549908 2.549906)
			(end 1.549908 2.253996)
			(stroke
				(width 0.1524)
				(type default)
			)
			(layer "F.SilkS")
		)
		(fp_line
			(start -1.549908 2.253996)
			(end -1.549908 2.549906)
			(stroke
				(width 0.1524)
				(type default)
			)
			(layer "F.SilkS")
		)
		(fp_line
			(start 1.549908 -2.253996)
			(end 1.549908 -2.549906)
			(stroke
				(width 0.1524)
				(type default)
			)
			(layer "F.SilkS")
		)
		(fp_line
			(start -1.549908 -2.549906)
			(end -1.549908 -2.251964)
			(stroke
				(width 0.1524)
				(type default)
			)
			(layer "F.SilkS")
		)
		(fp_line
			(start -0.752094 -2.549906)
			(end -1.549908 -2.549906)
			(stroke
				(width 0.1524)
				(type default)
			)
			(layer "F.SilkS")
		)
		(fp_line
			(start 0.2413 -2.549906)
			(end -0.2413 -2.549906)
			(stroke
				(width 0.1524)
				(type default)
			)
			(layer "F.SilkS")
		)
		(fp_line
			(start 1.549908 -2.549906)
			(end 0.752094 -2.549906)
			(stroke
				(width 0.1524)
				(type default)
			)
			(layer "F.SilkS")
		)
		(fp_poly
			(pts
				(xy -1.724152 -2.437892) (xy -2.627376 -2.739136) (xy -2.025396 -3.341116)
			)
			(stroke
				(width 0)
				(type default)
			)
			(fill yes)
			(layer "F.SilkS")
		)
		(fp_line
			(start -1.549908 2.549906)
			(end 1.549908 2.549906)
			(stroke
				(width 0.1)
				(type default)
			)
			(layer "F.Fab")
		)
		(fp_line
			(start 1.549908 2.549906)
			(end 1.549908 -2.549906)
			(stroke
				(width 0.1)
				(type default)
			)
			(layer "F.Fab")
		)
		(fp_line
			(start -1.549908 -2.549906)
			(end -1.549908 2.549906)
			(stroke
				(width 0.1)
				(type default)
			)
			(layer "F.Fab")
		)
		(fp_line
			(start 1.549908 -2.549906)
			(end -1.549908 -2.549906)
			(stroke
				(width 0.1)
				(type default)
			)
			(layer "F.Fab")
		)
		(fp_poly
			(pts
				(xy -1.891538 -1.999996) (xy -2.7432 -1.574292) (xy -2.7432 -2.4257)
			)
			(stroke
				(width 0)
				(type default)
			)
			(fill yes)
			(layer "F.Fab")
		)
		(fp_text user "10"
			(at -1.4224 3.253232 270)
			(unlocked yes)
			(layer "F.SilkS")
			(effects
				(font
					(size 0.635 0.4064)
					(thickness 0.1524)
				)
			)
		)
		(fp_text user "11"
			(at 1.303528 2.912364 270)
			(unlocked yes)
			(layer "F.SilkS")
			(effects
				(font
					(size 0.635 0.4064)
					(thickness 0.1524)
				)
			)
		)
		(fp_text user "9"
			(at -2.338832 2.5908 180)
			(unlocked yes)
			(layer "F.SilkS")
			(effects
				(font
					(size 0.635 0.4064)
					(thickness 0.1524)
				)
			)
		)
		(fp_text user "12"
			(at 2.460244 1.136904 180)
			(unlocked yes)
			(layer "F.SilkS")
			(effects
				(font
					(size 0.635 0.4064)
					(thickness 0.1524)
				)
			)
		)
		(fp_text user "21_22"
			(at 0.429006 -3.467608 270)
			(unlocked yes)
			(layer "F.SilkS")
			(effects
				(font
					(size 0.635 0.4064)
					(thickness 0.1524)
				)
			)
		)
		(fp_text user "20"
			(at 2.31902 -3.75666 180)
			(unlocked yes)
			(layer "F.SilkS")
			(effects
				(font
					(size 0.635 0.4064)
					(thickness 0.1524)
				)
			)
		)
		(fp_text user "11"
			(at 1.1938 3.329432 270)
			(unlocked yes)
			(layer "F.Fab")
			(effects
				(font
					(size 0.635 0.4064)
					(thickness 0.1524)
				)
			)
		)
		(fp_text user "10"
			(at -1.4224 3.253232 270)
			(unlocked yes)
			(layer "F.Fab")
			(effects
				(font
					(size 0.635 0.4064)
					(thickness 0.1524)
				)
			)
		)
		(fp_text user "12"
			(at 2.207768 2.7178 180)
			(unlocked yes)
			(layer "F.Fab")
			(effects
				(font
					(size 0.635 0.4064)
					(thickness 0.1524)
				)
			)
		)
		(fp_text user "9"
			(at -2.338832 2.5908 180)
			(unlocked yes)
			(layer "F.Fab")
			(effects
				(font
					(size 0.635 0.4064)
					(thickness 0.1524)
				)
			)
		)
		(fp_text user "20"
			(at 2.055368 -2.7686 180)
			(unlocked yes)
			(layer "F.Fab")
			(effects
				(font
					(size 0.635 0.4064)
					(thickness 0.1524)
				)
			)
		)
		(fp_text user "21_22"
			(at -0.0762 -3.401568 270)
			(unlocked yes)
			(layer "F.Fab")
			(effects
				(font
					(size 0.635 0.4064)
					(thickness 0.1524)
				)
			)
		)
		(pad "1" smd circle
			(at -1.374902 -1.999996 180)
			(size 0 0)
			(layers "F.Cu" "F.Mask" "F.Paste")
			(net "P12V_NIC4_CO_EN")
		)
		(pad "2" smd rect
			(at -1.400048 -1.500124 180)
			(size 0.254 0.8128)
			(layers "F.Cu" "F.Mask" "F.Paste")
			(net "GND")
		)
		(pad "3" smd rect
			(at -1.400048 -0.999998 180)
			(size 0.254 0.8128)
			(layers "F.Cu" "F.Mask" "F.Paste")
			(net "GND")
		)
		(pad "4" smd rect
			(at -1.400048 -0.499872 180)
			(size 0.254 0.8128)
			(layers "F.Cu" "F.Mask" "F.Paste")
			(net "P12V_NIC4_CO_TIMER")
		)
		(pad "5" smd rect
			(at -1.400048 0 180)
			(size 0.254 0.8128)
			(layers "F.Cu" "F.Mask" "F.Paste")
			(net "P12V_NIC4_CO_ISET")
		)
		(pad "6" smd rect
			(at -1.400048 0.499872 180)
			(size 0.254 0.8128)
			(layers "F.Cu" "F.Mask" "F.Paste")
			(net "P12V_NIC4_CO_SS")
		)
		(pad "7" smd rect
			(at -1.400048 0.999998 180)
			(size 0.254 0.8128)
			(layers "F.Cu" "F.Mask" "F.Paste")
			(net "GND")
		)
		(pad "8" smd rect
			(at -1.400048 1.500124 180)
			(size 0.254 0.8128)
			(layers "F.Cu" "F.Mask" "F.Paste")
			(net "P12V_NIC4_CO_IMON_VR")
		)
		(pad "9" smd rect
			(at -1.400048 1.999996 180)
			(size 0.254 0.8128)
			(layers "F.Cu" "F.Mask" "F.Paste")
			(net "P12V_NIC4_CO_FLTB")
		)
		(pad "10" smd rect
			(at -0.499872 2.400046 270)
			(size 0.254 0.8128)
			(layers "F.Cu" "F.Mask" "F.Paste")
			(net "PWRGD_P12V_NIC4_CO")
		)
		(pad "11" smd rect
			(at 0.499872 2.400046 270)
			(size 0.254 0.8128)
			(layers "F.Cu" "F.Mask" "F.Paste")
			(net "P12V_NIC4_CO_OV_FB")
		)
		(pad "12" smd rect
			(at 1.400048 1.999996 180)
			(size 0.254 0.8128)
			(layers "F.Cu" "F.Mask" "F.Paste")
			(net "P12V_NIC4_CO_AVIN_PD")
		)
		(pad "13" smd rect
			(at 1.400048 1.500124 180)
			(size 0.254 0.8128)
			(layers "F.Cu" "F.Mask" "F.Paste")
			(net "P12V_NIC4_R")
		)
		(pad "14" smd rect
			(at 1.400048 0.999998 180)
			(size 0.254 0.8128)
			(layers "F.Cu" "F.Mask" "F.Paste")
			(net "P12V_NIC4_R")
		)
		(pad "15" smd rect
			(at 1.400048 0.499872 180)
			(size 0.254 0.8128)
			(layers "F.Cu" "F.Mask" "F.Paste")
			(net "P12V_NIC4_R")
		)
		(pad "16" smd rect
			(at 1.400048 0 180)
			(size 0.254 0.8128)
			(layers "F.Cu" "F.Mask" "F.Paste")
			(net "P12V_NIC4_R")
		)
		(pad "17" smd rect
			(at 1.400048 -0.499872 180)
			(size 0.254 0.8128)
			(layers "F.Cu" "F.Mask" "F.Paste")
			(net "P12V_NIC4_R")
		)
		(pad "18" smd rect
			(at 1.400048 -0.999998 180)
			(size 0.254 0.8128)
			(layers "F.Cu" "F.Mask" "F.Paste")
			(net "P12V_NIC4_R")
		)
		(pad "19" smd rect
			(at 1.400048 -1.500124 180)
			(size 0.254 0.8128)
			(layers "F.Cu" "F.Mask" "F.Paste")
			(net "P12V_NIC4_R")
		)
		(pad "20" smd rect
			(at 1.400048 -1.999996 180)
			(size 0.254 0.8128)
			(layers "F.Cu" "F.Mask" "F.Paste")
			(net "P12V_NIC4_R")
		)
		(pad "21_22" smd circle
			(at 0.499872 -2.337562 180)
			(size 0 0)
			(layers "F.Cu" "F.Mask" "F.Paste")
			(net "P12V_AUX")
		)
		(pad "23" smd rect
			(at 0 -1.100074 180)
			(size 0.254 1.27)
			(layers "F.Cu" "F.Mask" "F.Paste")
			(net "P12V_AUX")
		)
		(pad "24" smd rect
			(at 0 -0.199898 180)
			(size 0.254 1.27)
			(layers "F.Cu" "F.Mask" "F.Paste")
			(net "P12V_AUX")
		)
		(pad "25" smd rect
			(at 0 0.700024 180)
			(size 0.254 1.27)
			(layers "F.Cu" "F.Mask" "F.Paste")
			(net "P12V_AUX")
		)
		(pad "26" smd rect
			(at 0 1.599946 180)
			(size 0.254 1.27)
			(layers "F.Cu" "F.Mask" "F.Paste")
			(net "P12V_AUX")
		)
	)
	(footprint ""
		(layer "F.Cu")
		(at 295.77919 -195.362068 90)
		(property "Reference" "R3391"
			(at 0 0 90)
			(layer "F.SilkS")
			(hide yes)
			(effects
				(font
					(size 1.27 1.27)
				)
			)
		)
		(property "Value" ""
			(at 0 0 90)
			(layer "F.Fab")
			(effects
				(font
					(size 1.27 1.27)
				)
			)
		)
		(duplicate_pad_numbers_are_jumpers no)
		(fp_line
			(start 0.7874 -0.4064)
			(end 0.7874 0.4064)
			(stroke
				(width 0.1524)
				(type default)
			)
			(layer "F.SilkS")
		)
		(fp_line
			(start -0.7874 -0.4064)
			(end 0.7874 -0.4064)
			(stroke
				(width 0.1524)
				(type default)
			)
			(layer "F.SilkS")
		)
		(fp_line
			(start 0.7874 0.4064)
			(end -0.7874 0.4064)
			(stroke
				(width 0.1524)
				(type default)
			)
			(layer "F.SilkS")
		)
		(fp_line
			(start -0.7874 0.4064)
			(end -0.7874 -0.4064)
			(stroke
				(width 0.1524)
				(type default)
			)
			(layer "F.SilkS")
		)
		(fp_line
			(start -0.12065 -0.305054)
			(end -0.12065 -0.2794)
			(stroke
				(width 0.1)
				(type default)
			)
			(layer "F.Fab")
		)
		(fp_line
			(start -0.67945 -0.305054)
			(end -0.12065 -0.305054)
			(stroke
				(width 0.1)
				(type default)
			)
			(layer "F.Fab")
		)
		(fp_line
			(start 0.67945 -0.3048)
			(end 0.67945 0.3048)
			(stroke
				(width 0.1)
				(type default)
			)
			(layer "F.Fab")
		)
		(fp_line
			(start 0.12065 -0.3048)
			(end 0.67945 -0.3048)
			(stroke
				(width 0.1)
				(type default)
			)
			(layer "F.Fab")
		)
		(fp_line
			(start 0.12065 -0.2794)
			(end 0.12065 -0.3048)
			(stroke
				(width 0.1)
				(type default)
			)
			(layer "F.Fab")
		)
		(fp_line
			(start -0.12065 -0.2794)
			(end 0.12065 -0.2794)
			(stroke
				(width 0.1)
				(type default)
			)
			(layer "F.Fab")
		)
		(fp_line
			(start 0.120396 0.2794)
			(end -0.12065 0.2794)
			(stroke
				(width 0.1)
				(type default)
			)
			(layer "F.Fab")
		)
		(fp_line
			(start -0.12065 0.2794)
			(end -0.12065 0.3048)
			(stroke
				(width 0.1)
				(type default)
			)
			(layer "F.Fab")
		)
		(fp_line
			(start 0.67945 0.3048)
			(end 0.120396 0.3048)
			(stroke
				(width 0.1)
				(type default)
			)
			(layer "F.Fab")
		)
		(fp_line
			(start 0.120396 0.3048)
			(end 0.120396 0.2794)
			(stroke
				(width 0.1)
				(type default)
			)
			(layer "F.Fab")
		)
		(fp_line
			(start -0.12065 0.3048)
			(end -0.67945 0.3048)
			(stroke
				(width 0.1)
				(type default)
			)
			(layer "F.Fab")
		)
		(fp_line
			(start -0.67945 0.3048)
			(end -0.67945 -0.305054)
			(stroke
				(width 0.1)
				(type default)
			)
			(layer "F.Fab")
		)
		(pad "1" smd circle
			(at -0.40005 0 90)
			(size 0 0)
			(layers "F.Cu" "F.Mask" "F.Paste")
			(net "SPI_BIC1_CLK_R2")
		)
		(pad "2" smd circle
			(at 0.40005 0 90)
			(size 0 0)
			(layers "F.Cu" "F.Mask" "F.Paste")
			(net "SPI_BIC1_CLK_R4")
		)
	)
	(footprint ""
		(layer "F.Cu")
		(at 77.064362 -29.079952 180)
		(property "Reference" "R6200"
			(at 0 0 180)
			(layer "F.SilkS")
			(hide yes)
			(effects
				(font
					(size 1.27 1.27)
				)
			)
		)
		(property "Value" ""
			(at 0 0 180)
			(layer "F.Fab")
			(effects
				(font
					(size 1.27 1.27)
				)
			)
		)
		(duplicate_pad_numbers_are_jumpers no)
		(fp_line
			(start 0.7874 0.4064)
			(end -0.7874 0.4064)
			(stroke
				(width 0.1524)
				(type default)
			)
			(layer "F.SilkS")
		)
		(fp_line
			(start 0.7874 -0.4064)
			(end 0.7874 0.4064)
			(stroke
				(width 0.1524)
				(type default)
			)
			(layer "F.SilkS")
		)
		(fp_line
			(start -0.7874 0.4064)
			(end -0.7874 -0.4064)
			(stroke
				(width 0.1524)
				(type default)
			)
			(layer "F.SilkS")
		)
		(fp_line
			(start -0.7874 -0.4064)
			(end 0.7874 -0.4064)
			(stroke
				(width 0.1524)
				(type default)
			)
			(layer "F.SilkS")
		)
		(fp_line
			(start 0.67945 0.3048)
			(end 0.120396 0.3048)
			(stroke
				(width 0.1)
				(type default)
			)
			(layer "F.Fab")
		)
		(fp_line
			(start 0.67945 -0.3048)
			(end 0.67945 0.3048)
			(stroke
				(width 0.1)
				(type default)
			)
			(layer "F.Fab")
		)
		(fp_line
			(start 0.12065 -0.2794)
			(end 0.12065 -0.3048)
			(stroke
				(width 0.1)
				(type default)
			)
			(layer "F.Fab")
		)
		(fp_line
			(start 0.12065 -0.3048)
			(end 0.67945 -0.3048)
			(stroke
				(width 0.1)
				(type default)
			)
			(layer "F.Fab")
		)
		(fp_line
			(start 0.120396 0.3048)
			(end 0.120396 0.2794)
			(stroke
				(width 0.1)
				(type default)
			)
			(layer "F.Fab")
		)
		(fp_line
			(start 0.120396 0.2794)
			(end -0.12065 0.2794)
			(stroke
				(width 0.1)
				(type default)
			)
			(layer "F.Fab")
		)
		(fp_line
			(start -0.12065 0.3048)
			(end -0.67945 0.3048)
			(stroke
				(width 0.1)
				(type default)
			)
			(layer "F.Fab")
		)
		(fp_line
			(start -0.12065 0.2794)
			(end -0.12065 0.3048)
			(stroke
				(width 0.1)
				(type default)
			)
			(layer "F.Fab")
		)
		(fp_line
			(start -0.12065 -0.2794)
			(end 0.12065 -0.2794)
			(stroke
				(width 0.1)
				(type default)
			)
			(layer "F.Fab")
		)
		(fp_line
			(start -0.12065 -0.305054)
			(end -0.12065 -0.2794)
			(stroke
				(width 0.1)
				(type default)
			)
			(layer "F.Fab")
		)
		(fp_line
			(start -0.67945 0.3048)
			(end -0.67945 -0.305054)
			(stroke
				(width 0.1)
				(type default)
			)
			(layer "F.Fab")
		)
		(fp_line
			(start -0.67945 -0.305054)
			(end -0.12065 -0.305054)
			(stroke
				(width 0.1)
				(type default)
			)
			(layer "F.Fab")
		)
		(pad "1" smd circle
			(at -0.40005 0 180)
			(size 0 0)
			(layers "F.Cu" "F.Mask" "F.Paste")
			(net "GND")
		)
		(pad "2" smd circle
			(at 0.40005 0 180)
			(size 0 0)
			(layers "F.Cu" "F.Mask" "F.Paste")
			(net "SSD2_PWRDIS_R")
		)
	)
)
